# SCM (Grand Teton) — schematic netlist excerpt (pin names and nets, part order shuffled) for the footprints in the layout excerpt that follows; sources: Cadence DE-HDL packaged netlist, KiCad conversion of 12092022_DA0F0TMDCD0_F0T_Management_Board_D_brd_V3_OCP.brd

U22  PI3PCIE3212ZBEX  IC  pkg QFN20_TH_0-5_2-5X4-5  page 29
  VDD0  = P3V3_AUX
  PD  = USB3_MUX_PD
  A0_P  = USB3_01_MUX_FB_TXP
  A0_N  = USB3_01_MUX_FB_TXN
  GND1  = GND
  VDD1  = P3V3_AUX
  A1_P  = USB3_01_MUX_FB_RXP
  A1_N  = USB3_01_MUX_FB_RXN
  SEL  = DEBUG_PORT_PRSNT
  VDD2  = P3V3_AUX
  GND2  = GND
  C1_N  = SMB_DEBUG_AUX_LVC3_USB_R2_SCL
  C1_P  = SMB_DEBUG_AUX_LVC3_USB_R2_SDA
  C0_N  = DEBUG_PORT_UART_TX
  C0_P  = DEBUG_PORT_UART_RX
  B1_N  = USB3_FPNL_RXN
  B1_P  = USB3_FPNL_RXP
  B0_N  = USB3_01_TXN_C
  B0_P  = USB3_01_TXP_C
  GND0  = GND
  TH  = NC

(kicad_pcb
	(version 20260206)
	(generator "pcbnew")
	(generator_version "10.0")
	(general
		(thickness 1.6)
		(legacy_teardrops no)
	)
	(paper "A4")
	(title_block
		(title "12092022_DA0F0TMDCD0_F0T_Management_Board_D_brd_V3_OCP.brd")
		(comment 1 "Grand Teton / footprint 1224 of 1440 (U22), pads 1-21 of 21")
	)
	(layers
		(0 "F.Cu" signal "TOP")
		(4 "In1.Cu" signal "GND")
		(6 "In2.Cu" signal "IN1")
		(8 "In3.Cu" signal "GND1")
		(10 "In4.Cu" signal "IN2")
		(12 "In5.Cu" signal "VCC")
		(14 "In6.Cu" signal "VCC1")
		(16 "In7.Cu" signal "IN3")
		(18 "In8.Cu" signal "GND2")
		(20 "In9.Cu" signal "IN4")
		(22 "In10.Cu" signal "GND3")
		(2 "B.Cu" signal "BOTTOM")
		(9 "F.Adhes" user "F.Adhesive")
		(11 "B.Adhes" user "B.Adhesive")
		(13 "F.Paste" user "Package Geometry/Pastemask Top")
		(15 "B.Paste" user "Package Geometry/Pastemask Bottom")
		(5 "F.SilkS" user "Ref Des/Silkscreen Top")
		(7 "B.SilkS" user "Ref Des/Silkscreen Bottom")
		(1 "F.Mask" user "Board Geometry/Soldermask Top")
		(3 "B.Mask" user "Board Geometry/Soldermask Bottom")
		(17 "Dwgs.User" user "User.Drawings")
		(19 "Cmts.User" user "User.Comments")
		(21 "Eco1.User" user "User.Eco1")
		(23 "Eco2.User" user "User.Eco2")
		(25 "Edge.Cuts" user "Board Geometry/Outline")
		(27 "Margin" user)
		(31 "F.CrtYd" user "Package Geometry/Place Bound Top")
		(29 "B.CrtYd" user "Package Geometry/Place Bound Bottom")
		(35 "F.Fab" user "Ref Des/Assembly Top")
		(33 "B.Fab" user "Ref Des/Assembly Bottom")
	)
	(footprint ""
		(layer "B.Cu")
		(at 41.42994 -92.498926 -90)
		(property "Reference" "U22"
			(at 1.847596 4.09194 0)
			(unlocked yes)
			(layer "B.SilkS")
			(effects
				(font
					(size 0.7874 0.5842)
					(thickness 0.1524)
				)
				(justify left mirror)
			)
		)
		(property "Value" ""
			(at 0 0 90)
			(layer "B.Fab")
			(effects
				(font
					(size 1.27 1.27)
				)
				(justify mirror)
			)
		)
		(duplicate_pad_numbers_are_jumpers no)
		(pad "1" smd rect
			(at 0.249936 -2.100072 90)
			(size 0.2794 0.6604)
			(layers "B.Cu" "B.Mask" "B.Paste")
			(net "P3V3_AUX")
		)
		(pad "2" smd rect
			(at 1.100074 -1.75006 180)
			(size 0.2794 0.6604)
			(layers "B.Cu" "B.Mask" "B.Paste")
			(net "USB3_MUX_PD")
		)
		(pad "3" smd rect
			(at 1.100074 -1.249934 180)
			(size 0.2794 0.6604)
			(layers "B.Cu" "B.Mask" "B.Paste")
			(net "USB3_01_MUX_FB_TXP")
		)
		(pad "4" smd rect
			(at 1.100074 -0.750062 180)
			(size 0.2794 0.6604)
			(layers "B.Cu" "B.Mask" "B.Paste")
			(net "USB3_01_MUX_FB_TXN")
		)
		(pad "5" smd rect
			(at 1.100074 -0.249936 180)
			(size 0.2794 0.6604)
			(layers "B.Cu" "B.Mask" "B.Paste")
			(net "GND")
		)
		(pad "6" smd rect
			(at 1.100074 0.249936 180)
			(size 0.2794 0.6604)
			(layers "B.Cu" "B.Mask" "B.Paste")
			(net "P3V3_AUX")
		)
		(pad "7" smd rect
			(at 1.100074 0.750062 180)
			(size 0.2794 0.6604)
			(layers "B.Cu" "B.Mask" "B.Paste")
			(net "USB3_01_MUX_FB_RXP")
		)
		(pad "8" smd rect
			(at 1.100074 1.249934 180)
			(size 0.2794 0.6604)
			(layers "B.Cu" "B.Mask" "B.Paste")
			(net "USB3_01_MUX_FB_RXN")
		)
		(pad "9" smd rect
			(at 1.100074 1.75006 180)
			(size 0.2794 0.6604)
			(layers "B.Cu" "B.Mask" "B.Paste")
			(net "DEBUG_PORT_PRSNT")
		)
		(pad "10" smd rect
			(at 0.249936 2.100072 90)
			(size 0.2794 0.6604)
			(layers "B.Cu" "B.Mask" "B.Paste")
			(net "P3V3_AUX")
		)
		(pad "11" smd rect
			(at -0.249936 2.100072 90)
			(size 0.2794 0.6604)
			(layers "B.Cu" "B.Mask" "B.Paste")
			(net "GND")
		)
		(pad "12" smd rect
			(at -1.100074 1.75006 180)
			(size 0.2794 0.6604)
			(layers "B.Cu" "B.Mask" "B.Paste")
			(net "SMB_DEBUG_AUX_LVC3_USB_R2_SCL")
		)
		(pad "13" smd rect
			(at -1.100074 1.249934 180)
			(size 0.2794 0.6604)
			(layers "B.Cu" "B.Mask" "B.Paste")
			(net "SMB_DEBUG_AUX_LVC3_USB_R2_SDA")
		)
		(pad "14" smd rect
			(at -1.100074 0.750062 180)
			(size 0.2794 0.6604)
			(layers "B.Cu" "B.Mask" "B.Paste")
			(net "DEBUG_PORT_UART_TX")
		)
		(pad "15" smd rect
			(at -1.100074 0.249936 180)
			(size 0.2794 0.6604)
			(layers "B.Cu" "B.Mask" "B.Paste")
			(net "DEBUG_PORT_UART_RX")
		)
		(pad "16" smd rect
			(at -1.100074 -0.249936 180)
			(size 0.2794 0.6604)
			(layers "B.Cu" "B.Mask" "B.Paste")
			(net "USB3_FPNL_RXN")
		)
		(pad "17" smd rect
			(at -1.100074 -0.750062 180)
			(size 0.2794 0.6604)
			(layers "B.Cu" "B.Mask" "B.Paste")
			(net "USB3_FPNL_RXP")
		)
		(pad "18" smd rect
			(at -1.100074 -1.249934 180)
			(size 0.2794 0.6604)
			(layers "B.Cu" "B.Mask" "B.Paste")
			(net "USB3_01_TXN_C")
		)
		(pad "19" smd rect
			(at -1.100074 -1.75006 180)
			(size 0.2794 0.6604)
			(layers "B.Cu" "B.Mask" "B.Paste")
			(net "USB3_01_TXP_C")
		)
		(pad "20" smd rect
			(at -0.249936 -2.100072 90)
			(size 0.2794 0.6604)
			(layers "B.Cu" "B.Mask" "B.Paste")
			(net "GND")
		)
		(pad "TH" smd rect
			(at 0 0 90)
			(size 0.9144 2.921)
			(layers "B.Cu" "B.Mask" "B.Paste")
			(net "Net_321")
		)
	)
)
